# S9S_MB_2U (Grand Teton) — schematic netlist excerpt (pin names and nets, part order shuffled) for the footprints in the layout excerpt that follows; sources: Cadence DE-HDL packaged netlist, KiCad conversion of 03242023_DA0F0TMBIJ0_F0T_Motherboard_J_brd_V01_OCP.brd

R413  Q_RES  100K 1% CHIP  pkg 0402LF  page 159 : A = GND ; B = FM_OCP_V3_2_PWR_GOOD
PR275  Q_RES  0 5% CHIP  pkg 0402LF  page 292 : A = PVCCINFAON_CPU1_CSPIN ; B = GND

(kicad_pcb
	(version 20260206)
	(generator "pcbnew")
	(generator_version "10.0")
	(general
		(thickness 1.6)
		(legacy_teardrops no)
	)
	(paper "A4")
	(title_block
		(title "03242023_DA0F0TMBIJ0_F0T_Motherboard_J_brd_V01_OCP.brd")
		(comment 1 "Grand Teton / footprints 5275-5276 of 6105")
	)
	(layers
		(0 "F.Cu" signal "TOP")
		(4 "In1.Cu" signal "GND")
		(6 "In2.Cu" signal "IN1")
		(8 "In3.Cu" signal "GND1")
		(10 "In4.Cu" signal "IN2")
		(12 "In5.Cu" signal "GND2")
		(14 "In6.Cu" signal "IN3")
		(16 "In7.Cu" signal "GND3")
		(18 "In8.Cu" signal "VCC")
		(20 "In9.Cu" signal "VCC1")
		(22 "In10.Cu" signal "GND4")
		(24 "In11.Cu" signal "IN4")
		(26 "In12.Cu" signal "GND5")
		(28 "In13.Cu" signal "IN5")
		(30 "In14.Cu" signal "GND6")
		(32 "In15.Cu" signal "IN6")
		(34 "In16.Cu" signal "GND7")
		(2 "B.Cu" signal "BOTTOM")
		(9 "F.Adhes" user "F.Adhesive")
		(11 "B.Adhes" user "B.Adhesive")
		(13 "F.Paste" user "Package Geometry/Pastemask Top")
		(15 "B.Paste" user "Package Geometry/Pastemask Bottom")
		(5 "F.SilkS" user "Ref Des/Silkscreen Top")
		(7 "B.SilkS" user "Ref Des/Silkscreen Bottom")
		(1 "F.Mask" user "Board Geometry/Soldermask Top")
		(3 "B.Mask" user "Board Geometry/Soldermask Bottom")
		(17 "Dwgs.User" user "User.Drawings")
		(19 "Cmts.User" user "User.Comments")
		(21 "Eco1.User" user "User.Eco1")
		(23 "Eco2.User" user "User.Eco2")
		(25 "Edge.Cuts" user "Board Geometry/Outline")
		(27 "Margin" user)
		(31 "F.CrtYd" user "Package Geometry/Place Bound Top")
		(29 "B.CrtYd" user "Package Geometry/Place Bound Bottom")
		(35 "F.Fab" user "Ref Des/Assembly Top")
		(33 "B.Fab" user "Ref Des/Assembly Bottom")
	)
	(footprint ""
		(layer "B.Cu")
		(at 30.163516 -129.000758 180)
		(property "Reference" "PR275"
			(at 0 0 0)
			(layer "B.SilkS")
			(hide yes)
			(effects
				(font
					(size 1.27 1.27)
				)
				(justify mirror)
			)
		)
		(property "Value" ""
			(at 0 0 0)
			(layer "B.Fab")
			(effects
				(font
					(size 1.27 1.27)
				)
				(justify mirror)
			)
		)
		(duplicate_pad_numbers_are_jumpers no)
		(fp_line
			(start 0.7874 0.4064)
			(end 0.7874 -0.4064)
			(stroke
				(width 0.1524)
				(type default)
			)
			(layer "B.SilkS")
		)
		(fp_line
			(start 0.7874 -0.4064)
			(end -0.7874 -0.4064)
			(stroke
				(width 0.1524)
				(type default)
			)
			(layer "B.SilkS")
		)
		(fp_line
			(start -0.7874 0.4064)
			(end 0.7874 0.4064)
			(stroke
				(width 0.1524)
				(type default)
			)
			(layer "B.SilkS")
		)
		(fp_line
			(start -0.7874 -0.4064)
			(end -0.7874 0.4064)
			(stroke
				(width 0.1524)
				(type default)
			)
			(layer "B.SilkS")
		)
		(fp_line
			(start 0.67945 0.3048)
			(end 0.67945 -0.305054)
			(stroke
				(width 0.1)
				(type default)
			)
			(layer "B.Fab")
		)
		(fp_line
			(start 0.67945 -0.305054)
			(end 0.12065 -0.305054)
			(stroke
				(width 0.1)
				(type default)
			)
			(layer "B.Fab")
		)
		(fp_line
			(start 0.12065 0.3048)
			(end 0.67945 0.3048)
			(stroke
				(width 0.1)
				(type default)
			)
			(layer "B.Fab")
		)
		(fp_line
			(start 0.12065 0.2794)
			(end 0.12065 0.3048)
			(stroke
				(width 0.1)
				(type default)
			)
			(layer "B.Fab")
		)
		(fp_line
			(start 0.12065 -0.2794)
			(end -0.12065 -0.2794)
			(stroke
				(width 0.1)
				(type default)
			)
			(layer "B.Fab")
		)
		(fp_line
			(start 0.12065 -0.305054)
			(end 0.12065 -0.2794)
			(stroke
				(width 0.1)
				(type default)
			)
			(layer "B.Fab")
		)
		(fp_line
			(start -0.120396 0.3048)
			(end -0.120396 0.2794)
			(stroke
				(width 0.1)
				(type default)
			)
			(layer "B.Fab")
		)
		(fp_line
			(start -0.120396 0.2794)
			(end 0.12065 0.2794)
			(stroke
				(width 0.1)
				(type default)
			)
			(layer "B.Fab")
		)
		(fp_line
			(start -0.12065 -0.2794)
			(end -0.12065 -0.3048)
			(stroke
				(width 0.1)
				(type default)
			)
			(layer "B.Fab")
		)
		(fp_line
			(start -0.12065 -0.3048)
			(end -0.67945 -0.3048)
			(stroke
				(width 0.1)
				(type default)
			)
			(layer "B.Fab")
		)
		(fp_line
			(start -0.67945 0.3048)
			(end -0.120396 0.3048)
			(stroke
				(width 0.1)
				(type default)
			)
			(layer "B.Fab")
		)
		(fp_line
			(start -0.67945 -0.3048)
			(end -0.67945 0.3048)
			(stroke
				(width 0.1)
				(type default)
			)
			(layer "B.Fab")
		)
		(pad "1" smd circle
			(at 0.40005 0)
			(size 0 0)
			(layers "B.Cu" "B.Mask" "B.Paste")
			(net "PVCCINFAON_CPU1_CSPIN")
		)
		(pad "2" smd circle
			(at -0.40005 0)
			(size 0 0)
			(layers "B.Cu" "B.Mask" "B.Paste")
			(net "GND")
		)
	)
	(footprint ""
		(layer "B.Cu")
		(at 77.90688 -11.267948 -90)
		(property "Reference" "R413"
			(at 0 0 90)
			(layer "B.SilkS")
			(hide yes)
			(effects
				(font
					(size 1.27 1.27)
				)
				(justify mirror)
			)
		)
		(property "Value" ""
			(at 0 0 90)
			(layer "B.Fab")
			(effects
				(font
					(size 1.27 1.27)
				)
				(justify mirror)
			)
		)
		(duplicate_pad_numbers_are_jumpers no)
		(fp_line
			(start -0.7874 0.4064)
			(end 0.7874 0.4064)
			(stroke
				(width 0.1524)
				(type default)
			)
			(layer "B.SilkS")
		)
		(fp_line
			(start 0.7874 0.4064)
			(end 0.7874 -0.4064)
			(stroke
				(width 0.1524)
				(type default)
			)
			(layer "B.SilkS")
		)
		(fp_line
			(start -0.7874 -0.4064)
			(end -0.7874 0.4064)
			(stroke
				(width 0.1524)
				(type default)
			)
			(layer "B.SilkS")
		)
		(fp_line
			(start 0.7874 -0.4064)
			(end -0.7874 -0.4064)
			(stroke
				(width 0.1524)
				(type default)
			)
			(layer "B.SilkS")
		)
		(fp_line
			(start -0.67945 0.3048)
			(end -0.120396 0.3048)
			(stroke
				(width 0.1)
				(type default)
			)
			(layer "B.Fab")
		)
		(fp_line
			(start -0.120396 0.3048)
			(end -0.120396 0.2794)
			(stroke
				(width 0.1)
				(type default)
			)
			(layer "B.Fab")
		)
		(fp_line
			(start 0.12065 0.3048)
			(end 0.67945 0.3048)
			(stroke
				(width 0.1)
				(type default)
			)
			(layer "B.Fab")
		)
		(fp_line
			(start 0.67945 0.3048)
			(end 0.67945 -0.305054)
			(stroke
				(width 0.1)
				(type default)
			)
			(layer "B.Fab")
		)
		(fp_line
			(start -0.120396 0.2794)
			(end 0.12065 0.2794)
			(stroke
				(width 0.1)
				(type default)
			)
			(layer "B.Fab")
		)
		(fp_line
			(start 0.12065 0.2794)
			(end 0.12065 0.3048)
			(stroke
				(width 0.1)
				(type default)
			)
			(layer "B.Fab")
		)
		(fp_line
			(start -0.12065 -0.2794)
			(end -0.12065 -0.3048)
			(stroke
				(width 0.1)
				(type default)
			)
			(layer "B.Fab")
		)
		(fp_line
			(start 0.12065 -0.2794)
			(end -0.12065 -0.2794)
			(stroke
				(width 0.1)
				(type default)
			)
			(layer "B.Fab")
		)
		(fp_line
			(start -0.67945 -0.3048)
			(end -0.67945 0.3048)
			(stroke
				(width 0.1)
				(type default)
			)
			(layer "B.Fab")
		)
		(fp_line
			(start -0.12065 -0.3048)
			(end -0.67945 -0.3048)
			(stroke
				(width 0.1)
				(type default)
			)
			(layer "B.Fab")
		)
		(fp_line
			(start 0.12065 -0.305054)
			(end 0.12065 -0.2794)
			(stroke
				(width 0.1)
				(type default)
			)
			(layer "B.Fab")
		)
		(fp_line
			(start 0.67945 -0.305054)
			(end 0.12065 -0.305054)
			(stroke
				(width 0.1)
				(type default)
			)
			(layer "B.Fab")
		)
		(pad "1" smd circle
			(at 0.40005 0 90)
			(size 0 0)
			(layers "B.Cu" "B.Mask" "B.Paste")
			(net "GND")
		)
		(pad "2" smd circle
			(at -0.40005 0 90)
			(size 0 0)
			(layers "B.Cu" "B.Mask" "B.Paste")
			(net "FM_OCP_V3_2_PWR_GOOD")
		)
	)
)
